# BASEBOARD_FAB2 (Tioga Pass) — schematic netlist excerpt (pin names and nets, part order shuffled) for the footprints in the layout excerpt that follows; sources: Cadence DE-HDL packaged netlist, KiCad conversion of Wiwynn_Tioga_Pass_MB.brd

R24W1  RES  3.3K 5% CHIP  pkg 0402  page 138 : A = P3V3_STBY ; B = SMB_SLOTX24_PCH_STBY_LVC3_SDA
C1M9  CAP  0.22UF 16V 10% X7R  pkg 0402  page 106 : A = P3E_CPU0_PE3_OCP_TXN<14> ; B = P3E_OCP_CPU0_PE3_C_TXN<14>
R3R4  RES  4.75K 1% CHIP  pkg 0402  page 94 : A = P3V3 ; B = H_CPU0_MEMDEF_MEMHOT

(kicad_pcb
	(version 20260206)
	(generator "pcbnew")
	(generator_version "10.0")
	(general
		(thickness 1.6)
		(legacy_teardrops no)
	)
	(paper "A4")
	(title_block
		(title "Wiwynn_Tioga_Pass_MB.brd")
		(comment 1 "Tioga Pass / footprints 3387-3389 of 4770")
	)
	(layers
		(0 "F.Cu" signal "TOP")
		(4 "In1.Cu" signal "L2GND")
		(6 "In2.Cu" signal "L3")
		(8 "In3.Cu" signal "L4GND")
		(10 "In4.Cu" signal "L5")
		(12 "In5.Cu" signal "L6GND")
		(14 "In6.Cu" signal "L7VCC")
		(16 "In7.Cu" signal "L8VCC")
		(18 "In8.Cu" signal "L9GND")
		(20 "In9.Cu" signal "L10")
		(22 "In10.Cu" signal "L11GND")
		(24 "In11.Cu" signal "L12")
		(26 "In12.Cu" signal "L13GND")
		(2 "B.Cu" signal "BOTTOM")
		(9 "F.Adhes" user "F.Adhesive")
		(11 "B.Adhes" user "B.Adhesive")
		(13 "F.Paste" user "Package Geometry/Pastemask Top")
		(15 "B.Paste" user "Package Geometry/Pastemask Bottom")
		(5 "F.SilkS" user "Ref Des/Silkscreen Top")
		(7 "B.SilkS" user "Ref Des/Silkscreen Bottom")
		(1 "F.Mask" user "Board Geometry/Soldermask Top")
		(3 "B.Mask" user "Board Geometry/Soldermask Bottom")
		(17 "Dwgs.User" user "User.Drawings")
		(19 "Cmts.User" user "User.Comments")
		(21 "Eco1.User" user "User.Eco1")
		(23 "Eco2.User" user "User.Eco2")
		(25 "Edge.Cuts" user "Board Geometry/Outline")
		(27 "Margin" user)
		(31 "F.CrtYd" user "Package Geometry/Place Bound Top")
		(29 "B.CrtYd" user "Package Geometry/Place Bound Bottom")
		(35 "F.Fab" user "Ref Des/Assembly Top")
		(33 "B.Fab" user "Ref Des/Assembly Bottom")
	)
	(footprint ""
		(layer "B.Cu")
		(at 462.026 -116.49202)
		(property "Reference" "C1M9"
			(at 0 0 0)
			(layer "B.SilkS")
			(hide yes)
			(effects
				(font
					(size 1.27 1.27)
				)
				(justify mirror)
			)
		)
		(property "Value" ""
			(at 0 0 0)
			(layer "B.Fab")
			(effects
				(font
					(size 1.27 1.27)
				)
				(justify mirror)
			)
		)
		(duplicate_pad_numbers_are_jumpers no)
		(fp_rect
			(start -0.3048 0.9906)
			(end 0.3048 -0.1016)
			(stroke
				(width 0)
				(type default)
			)
			(fill no)
			(layer "B.CrtYd")
		)
		(fp_line
			(start -0.3048 -0.1016)
			(end 0.3048 -0.1016)
			(stroke
				(width 0.1)
				(type default)
			)
			(layer "B.Fab")
		)
		(fp_line
			(start -0.3048 0.9906)
			(end -0.3048 -0.1016)
			(stroke
				(width 0.1)
				(type default)
			)
			(layer "B.Fab")
		)
		(fp_line
			(start 0.3048 -0.1016)
			(end 0.3048 0.9906)
			(stroke
				(width 0.1)
				(type default)
			)
			(layer "B.Fab")
		)
		(fp_line
			(start 0.3048 0.9906)
			(end -0.3048 0.9906)
			(stroke
				(width 0.1)
				(type default)
			)
			(layer "B.Fab")
		)
		(pad "1" smd rect
			(at 0 0 180)
			(size 0.508 0.508)
			(layers "B.Cu" "B.Mask" "B.Paste")
			(net "P3E_CPU0_PE3_OCP_TXN<14>")
		)
		(pad "2" smd rect
			(at 0 0.889 180)
			(size 0.508 0.508)
			(layers "B.Cu" "B.Mask" "B.Paste")
			(net "P3E_OCP_CPU0_PE3_C_TXN<14>")
		)
		(zone
			(layer "B.Cu")
			(hatch none 0.5)
			(connect_pads
				(clearance 0)
			)
			(min_thickness 0.25)
			(keepout
				(tracks allowed)
				(vias not_allowed)
				(pads allowed)
				(copperpour not_allowed)
				(footprints allowed)
			)
			(placement
				(enabled no)
				(sheetname "")
			)
			(fill
				(thermal_gap 0.5)
				(thermal_bridge_width 0.5)
				(island_removal_mode 0)
			)
			(polygon
				(pts
					(xy 461.772 -115.85702) (xy 462.28 -115.85702) (xy 462.28 -116.23802) (xy 461.772 -116.23802)
				)
			)
		)
	)
	(footprint ""
		(layer "B.Cu")
		(at 399.764758 -115.605814)
		(property "Reference" "R24W1"
			(at 0.8382 -0.67818 0)
			(unlocked yes)
			(layer "B.SilkS")
			(effects
				(font
					(size 0.4064 0.254)
					(thickness 0.1524)
				)
				(justify left mirror)
			)
		)
		(property "Value" ""
			(at 0 0 0)
			(layer "B.Fab")
			(effects
				(font
					(size 1.27 1.27)
				)
				(justify mirror)
			)
		)
		(duplicate_pad_numbers_are_jumpers no)
		(fp_poly
			(pts
				(xy 0.2794 -0.1016) (xy -0.2794 -0.1016) (xy -0.2794 0.9906) (xy 0.2794 0.9906)
			)
			(stroke
				(width 0)
				(type default)
			)
			(fill no)
			(layer "B.CrtYd")
		)
		(fp_line
			(start -0.2794 -0.1016)
			(end 0.2794 -0.1016)
			(stroke
				(width 0.1)
				(type default)
			)
			(layer "B.Fab")
		)
		(fp_line
			(start -0.2794 0.9906)
			(end -0.2794 -0.1016)
			(stroke
				(width 0.1)
				(type default)
			)
			(layer "B.Fab")
		)
		(fp_line
			(start 0.2794 -0.1016)
			(end 0.2794 0.9906)
			(stroke
				(width 0.1)
				(type default)
			)
			(layer "B.Fab")
		)
		(fp_line
			(start 0.2794 0.9906)
			(end -0.2794 0.9906)
			(stroke
				(width 0.1)
				(type default)
			)
			(layer "B.Fab")
		)
		(pad "1" smd rect
			(at 0 0 180)
			(size 0.508 0.508)
			(layers "B.Cu" "B.Mask" "B.Paste")
			(net "P3V3_STBY")
		)
		(pad "2" smd rect
			(at 0 0.889 180)
			(size 0.508 0.508)
			(layers "B.Cu" "B.Mask" "B.Paste")
			(net "SMB_SLOTX24_PCH_STBY_LVC3_SDA")
		)
		(zone
			(layer "B.Cu")
			(hatch none 0.5)
			(connect_pads
				(clearance 0)
			)
			(min_thickness 0.25)
			(keepout
				(tracks allowed)
				(vias not_allowed)
				(pads allowed)
				(copperpour not_allowed)
				(footprints allowed)
			)
			(placement
				(enabled no)
				(sheetname "")
			)
			(fill
				(thermal_gap 0.5)
				(thermal_bridge_width 0.5)
				(island_removal_mode 0)
			)
			(polygon
				(pts
					(xy 400.018758 -115.351814) (xy 399.510758 -115.351814) (xy 399.510758 -114.970814) (xy 400.018758 -114.970814)
				)
			)
		)
		(zone
			(layer "B.Cu")
			(hatch none 0.5)
			(connect_pads
				(clearance 0)
			)
			(min_thickness 0.25)
			(keepout
				(tracks not_allowed)
				(vias allowed)
				(pads allowed)
				(copperpour not_allowed)
				(footprints allowed)
			)
			(placement
				(enabled no)
				(sheetname "")
			)
			(fill
				(thermal_gap 0.5)
				(thermal_bridge_width 0.5)
				(island_removal_mode 0)
			)
			(polygon
				(pts
					(xy 400.018758 -114.970814) (xy 399.510758 -114.970814) (xy 399.510758 -115.351814) (xy 400.018758 -115.351814)
				)
			)
		)
	)
	(footprint ""
		(layer "B.Cu")
		(at 413.059118 -92.428314)
		(property "Reference" "R3R4"
			(at 0 0 0)
			(layer "B.SilkS")
			(hide yes)
			(effects
				(font
					(size 1.27 1.27)
				)
				(justify mirror)
			)
		)
		(property "Value" ""
			(at 0 0 0)
			(layer "B.Fab")
			(effects
				(font
					(size 1.27 1.27)
				)
				(justify mirror)
			)
		)
		(duplicate_pad_numbers_are_jumpers no)
		(fp_poly
			(pts
				(xy 0.2794 -0.1016) (xy -0.2794 -0.1016) (xy -0.2794 0.9906) (xy 0.2794 0.9906)
			)
			(stroke
				(width 0)
				(type default)
			)
			(fill no)
			(layer "B.CrtYd")
		)
		(fp_line
			(start -0.2794 -0.1016)
			(end 0.2794 -0.1016)
			(stroke
				(width 0.1)
				(type default)
			)
			(layer "B.Fab")
		)
		(fp_line
			(start -0.2794 0.9906)
			(end -0.2794 -0.1016)
			(stroke
				(width 0.1)
				(type default)
			)
			(layer "B.Fab")
		)
		(fp_line
			(start 0.2794 -0.1016)
			(end 0.2794 0.9906)
			(stroke
				(width 0.1)
				(type default)
			)
			(layer "B.Fab")
		)
		(fp_line
			(start 0.2794 0.9906)
			(end -0.2794 0.9906)
			(stroke
				(width 0.1)
				(type default)
			)
			(layer "B.Fab")
		)
		(pad "1" smd rect
			(at 0 0 180)
			(size 0.508 0.508)
			(layers "B.Cu" "B.Mask" "B.Paste")
			(net "P3V3")
		)
		(pad "2" smd rect
			(at 0 0.889 180)
			(size 0.508 0.508)
			(layers "B.Cu" "B.Mask" "B.Paste")
			(net "H_CPU0_MEMDEF_MEMHOT")
		)
		(zone
			(layer "B.Cu")
			(hatch none 0.5)
			(connect_pads
				(clearance 0)
			)
			(min_thickness 0.25)
			(keepout
				(tracks allowed)
				(vias not_allowed)
				(pads allowed)
				(copperpour not_allowed)
				(footprints allowed)
			)
			(placement
				(enabled no)
				(sheetname "")
			)
			(fill
				(thermal_gap 0.5)
				(thermal_bridge_width 0.5)
				(island_removal_mode 0)
			)
			(polygon
				(pts
					(xy 413.313118 -92.174314) (xy 412.805118 -92.174314) (xy 412.805118 -91.793314) (xy 413.313118 -91.793314)
				)
			)
		)
		(zone
			(layer "B.Cu")
			(hatch none 0.5)
			(connect_pads
				(clearance 0)
			)
			(min_thickness 0.25)
			(keepout
				(tracks not_allowed)
				(vias allowed)
				(pads allowed)
				(copperpour not_allowed)
				(footprints allowed)
			)
			(placement
				(enabled no)
				(sheetname "")
			)
			(fill
				(thermal_gap 0.5)
				(thermal_bridge_width 0.5)
				(island_removal_mode 0)
			)
			(polygon
				(pts
					(xy 413.313118 -91.793314) (xy 412.805118 -91.793314) (xy 412.805118 -92.174314) (xy 413.313118 -92.174314)
				)
			)
		)
	)
)
